(kicad_pcb
	(version 20260206)
	(generator "pcbnew")
	(generator_version "10.0")
	(general
		(thickness 1.21888)
		(legacy_teardrops no)
	)
	(paper "A4")
	(title_block
		(title "timecard-v9 — TimeCard-DC-V9_EXP.PcbDoc")
		(comment 1 "Time Appliance Project (Time Card) / footprints 278-289 of 402")
	)
	(layers
		(0 "F.Cu" signal "TOP")
		(4 "In1.Cu" signal "SGND")
		(6 "In2.Cu" signal "IN1")
		(8 "In3.Cu" signal "IN2")
		(10 "In4.Cu" signal "SGND1")
		(2 "B.Cu" signal "BOTTOM")
		(9 "F.Adhes" user "F.Adhesive")
		(11 "B.Adhes" user "B.Adhesive")
		(13 "F.Paste" user "Top Paste")
		(15 "B.Paste" user "Bottom Paste")
		(5 "F.SilkS" user "Top Overlay")
		(7 "B.SilkS" user "Bottom Overlay")
		(1 "F.Mask" user "Top Solder")
		(3 "B.Mask" user "Bottom Solder")
		(17 "Dwgs.User" user "User.Drawings")
		(19 "Cmts.User" user "User.Comments")
		(21 "Eco1.User" user "User.Eco1")
		(23 "Eco2.User" user "User.Eco2")
		(25 "Edge.Cuts" user)
		(27 "Margin" user)
		(31 "F.CrtYd" user "Top Courtyard")
		(29 "B.CrtYd" user "Bottom Courtyard")
		(35 "F.Fab" user "Top Component Center")
		(33 "B.Fab" user "Bottom Component Center")
	)
	(footprint "Vault:RESC1005X40X25ML05T05"
		(layer "B.Cu")
		(at 216.13831 124.41792)
		(property "Reference" "R180"
			(at -0.07071 -1.074789 0)
			(unlocked yes)
			(layer "B.SilkS")
			(effects
				(font
					(size 0.762 0.762)
					(thickness 0.254)
				)
				(justify mirror)
			)
		)
		(property "Value" "10K_5%_0402"
			(at -2.884671 -8.061875 270)
			(unlocked yes)
			(layer "B.SilkS")
			(hide yes)
			(effects
				(font
					(size 0.762 0.762)
					(thickness 0.254)
				)
				(justify mirror)
			)
		)
		(sheetname "09-USBUart_PPSMUX_UARTMUX")
		(sheetfile "09-USBUart_PPSMUX_UARTMUX.kicad_sch")
		(duplicate_pad_numbers_are_jumpers no)
		(pad "1" smd rect
			(at -0.5 0 270)
			(size 0.65 0.65)
			(layers "B.Cu" "B.Mask" "B.Paste")
			(net "NetR180_1")
		)
		(pad "2" smd rect
			(at 0.5 0 270)
			(size 0.65 0.65)
			(layers "B.Cu" "B.Mask" "B.Paste")
			(net "+5.0V")
		)
	)
	(footprint "Vault:FP-0402-L_1_0_1-W_0_5_0_1-IPC_C"
		(layer "B.Cu")
		(at 217.7466 121.4412)
		(property "Reference" "C105"
			(at 0.6718 -1.398079 0)
			(unlocked yes)
			(layer "B.SilkS")
			(effects
				(font
					(size 0.762 0.762)
					(thickness 0.2032)
				)
				(justify mirror)
			)
		)
		(property "Value" "0.1uF_25V_0402"
			(at -2.465551 -9.813815 270)
			(unlocked yes)
			(layer "B.SilkS")
			(hide yes)
			(effects
				(font
					(size 0.762 0.762)
					(thickness 0.2032)
				)
				(justify mirror)
			)
		)
		(sheetname "10-M2_GPS")
		(sheetfile "10-M2_GPS.kicad_sch")
		(duplicate_pad_numbers_are_jumpers no)
		(fp_line
			(start -0.65607 -0.7)
			(end 0.65607 -0.7)
			(stroke
				(width 0.2)
				(type solid)
			)
			(layer "B.SilkS")
		)
		(fp_line
			(start -0.65607 0.7)
			(end 0.65607 0.7)
			(stroke
				(width 0.2)
				(type solid)
			)
			(layer "B.SilkS")
		)
		(fp_line
			(start -0.75607 -0.4)
			(end 0.75607 -0.4)
			(stroke
				(width 0.2)
				(type solid)
			)
			(layer "B.CrtYd")
		)
		(fp_line
			(start -0.75607 0.4)
			(end -0.75607 -0.4)
			(stroke
				(width 0.2)
				(type solid)
			)
			(layer "B.CrtYd")
		)
		(fp_line
			(start -0.75607 0.4)
			(end 0.75607 0.4)
			(stroke
				(width 0.2)
				(type solid)
			)
			(layer "B.CrtYd")
		)
		(fp_line
			(start 0.75607 0.4)
			(end 0.75607 -0.4)
			(stroke
				(width 0.2)
				(type solid)
			)
			(layer "B.CrtYd")
		)
		(fp_line
			(start -0.75607 -0.4)
			(end 0.75607 -0.4)
			(stroke
				(width 0.2)
				(type solid)
			)
			(layer "B.Fab")
		)
		(fp_line
			(start -0.75607 0.4)
			(end -0.75607 -0.4)
			(stroke
				(width 0.2)
				(type solid)
			)
			(layer "B.Fab")
		)
		(fp_line
			(start -0.75607 0.4)
			(end 0.75607 0.4)
			(stroke
				(width 0.2)
				(type solid)
			)
			(layer "B.Fab")
		)
		(fp_line
			(start -0.5 0)
			(end 0.5 0)
			(stroke
				(width 0.1)
				(type solid)
			)
			(layer "B.Fab")
		)
		(fp_line
			(start 0 0.5)
			(end 0 -0.5)
			(stroke
				(width 0.1)
				(type solid)
			)
			(layer "B.Fab")
		)
		(fp_line
			(start 0.75607 0.4)
			(end 0.75607 -0.4)
			(stroke
				(width 0.2)
				(type solid)
			)
			(layer "B.Fab")
		)
		(fp_text user "${REFERENCE}"
			(at -0.00002 -0.09602 180)
			(unlocked yes)
			(layer "B.Fab")
			(effects
				(font
					(face "Arial")
					(size 0.63 0.63)
					(thickness 0.1)
				)
				(justify left bottom mirror)
			)
		)
		(pad "1" smd rect
			(at -0.36554 0)
			(size 0.58106 0.51213)
			(layers "B.Cu" "B.Mask" "B.Paste")
			(net "GNSS2_P3V3")
			(solder_mask_margin 0)
			(solder_paste_margin 0)
		)
		(pad "2" smd rect
			(at 0.36554 0)
			(size 0.58106 0.51213)
			(layers "B.Cu" "B.Mask" "B.Paste")
			(net "GND")
			(solder_mask_margin 0)
			(solder_paste_margin 0)
		)
	)
	(footprint "Vault:RESC1005X40X25ML10T10"
		(layer "B.Cu")
		(at 180.2716 90.1662 180)
		(property "Reference" "R61"
			(at 0.278605 -0.976921 0)
			(unlocked yes)
			(layer "B.SilkS")
			(effects
				(font
					(size 0.762 0.762)
					(thickness 0.2286)
				)
				(justify mirror)
			)
		)
		(property "Value" "2.2K_0.5%_0402"
			(at -2.732271 -9.534615 90)
			(unlocked yes)
			(layer "B.SilkS")
			(hide yes)
			(effects
				(font
					(size 0.762 0.762)
					(thickness 0.2286)
				)
				(justify mirror)
			)
		)
		(sheetname "03-POWER")
		(sheetfile "03-POWER.kicad_sch")
		(duplicate_pad_numbers_are_jumpers no)
		(pad "1" smd rect
			(at -0.475 0 90)
			(size 0.7 0.75)
			(layers "B.Cu" "B.Mask" "B.Paste")
			(net "NetR61_1")
		)
		(pad "2" smd rect
			(at 0.475 0 90)
			(size 0.7 0.75)
			(layers "B.Cu" "B.Mask" "B.Paste")
			(net "NetR61_2")
		)
	)
	(footprint "Vault:RESC1005X40X25LL05T10"
		(layer "B.Cu")
		(at 83.65354 94.32502)
		(property "Reference" "R186"
			(at 2.244598 -2.75504 270)
			(unlocked yes)
			(layer "B.SilkS")
			(effects
				(font
					(size 1.524 1.524)
					(thickness 0.254)
				)
				(justify mirror)
			)
		)
		(property "Value" "10K_1%_0402"
			(at -2.606802 -8.087315 270)
			(unlocked yes)
			(layer "B.SilkS")
			(hide yes)
			(effects
				(font
					(size 1.524 1.524)
					(thickness 0.254)
				)
				(justify mirror)
			)
		)
		(sheetname "05-GPS_IMU_SENSORS")
		(sheetfile "05-GPS_IMU_SENSORS.kicad_sch")
		(duplicate_pad_numbers_are_jumpers no)
		(pad "1" smd rect
			(at -0.375 0 270)
			(size 0.45 0.5)
			(layers "B.Cu" "B.Mask" "B.Paste")
			(net "+3.3V")
		)
		(pad "2" smd rect
			(at 0.375 0 270)
			(size 0.45 0.5)
			(layers "B.Cu" "B.Mask" "B.Paste")
			(net "MAC_FREQ_CTRL")
		)
	)
	(footprint "Vault:FP-0402-L_1_0_1-W_0_5_0_1-IPC_C"
		(layer "B.Cu")
		(at 168.1216 114.2912)
		(property "Reference" "C70"
			(at -0.3286 1.651931 0)
			(unlocked yes)
			(layer "B.SilkS")
			(effects
				(font
					(size 0.762 0.762)
					(thickness 0.2286)
				)
				(justify mirror)
			)
		)
		(property "Value" "0.1uF_25V_0402"
			(at -2.744961 -9.813805 270)
			(unlocked yes)
			(layer "B.SilkS")
			(hide yes)
			(effects
				(font
					(size 0.762 0.762)
					(thickness 0.2286)
				)
				(justify mirror)
			)
		)
		(sheetname "08-DIPSwitches_I2C")
		(sheetfile "08-DIPSwitches_I2C.kicad_sch")
		(duplicate_pad_numbers_are_jumpers no)
		(fp_line
			(start -0.65607 -0.7)
			(end 0.65606 -0.7)
			(stroke
				(width 0.2)
				(type solid)
			)
			(layer "B.SilkS")
		)
		(fp_line
			(start -0.65607 0.7)
			(end 0.65606 0.7)
			(stroke
				(width 0.2)
				(type solid)
			)
			(layer "B.SilkS")
		)
		(fp_line
			(start -0.75607 -0.4)
			(end 0.75606 -0.4)
			(stroke
				(width 0.2)
				(type solid)
			)
			(layer "B.CrtYd")
		)
		(fp_line
			(start -0.75607 0.4)
			(end -0.75607 -0.4)
			(stroke
				(width 0.2)
				(type solid)
			)
			(layer "B.CrtYd")
		)
		(fp_line
			(start -0.75607 0.4)
			(end 0.75606 0.4)
			(stroke
				(width 0.2)
				(type solid)
			)
			(layer "B.CrtYd")
		)
		(fp_line
			(start 0.75606 0.4)
			(end 0.75606 -0.4)
			(stroke
				(width 0.2)
				(type solid)
			)
			(layer "B.CrtYd")
		)
		(fp_line
			(start -0.75607 -0.4)
			(end 0.75606 -0.4)
			(stroke
				(width 0.2)
				(type solid)
			)
			(layer "B.Fab")
		)
		(fp_line
			(start -0.75607 0.4)
			(end -0.75607 -0.4)
			(stroke
				(width 0.2)
				(type solid)
			)
			(layer "B.Fab")
		)
		(fp_line
			(start -0.75607 0.4)
			(end 0.75606 0.4)
			(stroke
				(width 0.2)
				(type solid)
			)
			(layer "B.Fab")
		)
		(fp_line
			(start -0.5 0)
			(end 0.5 0)
			(stroke
				(width 0.1)
				(type solid)
			)
			(layer "B.Fab")
		)
		(fp_line
			(start 0 0.5)
			(end 0 -0.5)
			(stroke
				(width 0.1)
				(type solid)
			)
			(layer "B.Fab")
		)
		(fp_line
			(start 0.75606 0.4)
			(end 0.75606 -0.4)
			(stroke
				(width 0.2)
				(type solid)
			)
			(layer "B.Fab")
		)
		(fp_text user "${REFERENCE}"
			(at -0.00002 -0.09601 180)
			(unlocked yes)
			(layer "B.Fab")
			(effects
				(font
					(face "Arial")
					(size 0.63 0.63)
					(thickness 0.1)
				)
				(justify left bottom mirror)
			)
		)
		(pad "1" smd rect
			(at -0.36554 0)
			(size 0.58106 0.51213)
			(layers "B.Cu" "B.Mask" "B.Paste")
			(net "+3.3V")
			(solder_mask_margin 0)
			(solder_paste_margin 0)
		)
		(pad "2" smd rect
			(at 0.36553 0)
			(size 0.58106 0.51213)
			(layers "B.Cu" "B.Mask" "B.Paste")
			(net "GND")
			(solder_mask_margin 0)
			(solder_paste_margin 0)
		)
	)
	(footprint "Vault:CAPC1005X56X25NL10T15"
		(layer "B.Cu")
		(at 114.90572 84.8412 -90)
		(property "Reference" "C67"
			(at 0.2036 -2.542811 90)
			(unlocked yes)
			(layer "B.SilkS")
			(effects
				(font
					(size 0.762 0.762)
					(thickness 0.2286)
				)
				(justify mirror)
			)
		)
		(property "Value" "0.1uF_25V_0402"
			(at 2.069025 -2.567191 90)
			(unlocked yes)
			(layer "B.SilkS")
			(hide yes)
			(effects
				(font
					(size 0.762 0.762)
					(thickness 0.2286)
				)
				(justify mirror)
			)
		)
		(sheetname "05-GPS_IMU_SENSORS")
		(sheetfile "05-GPS_IMU_SENSORS.kicad_sch")
		(duplicate_pad_numbers_are_jumpers no)
		(pad "1" smd rect
			(at -0.44 0 180)
			(size 0.64 0.68)
			(layers "B.Cu" "B.Mask" "B.Paste")
			(net "GND")
		)
		(pad "2" smd rect
			(at 0.44 0 180)
			(size 0.64 0.68)
			(layers "B.Cu" "B.Mask" "B.Paste")
			(net "BNO_P3V3")
		)
	)
	(footprint "Vault:FP-0402-L_1_0_1-W_0_5_0_1-IPC_C"
		(layer "B.Cu")
		(at 120.3216 79.1162 -90)
		(property "Reference" "C107"
			(at -0.2032 -1.573069 270)
			(unlocked yes)
			(layer "B.SilkS")
			(effects
				(font
					(size 0.762 0.762)
					(thickness 0.2032)
				)
				(justify mirror)
			)
		)
		(property "Value" "0.1uF_25V_0402"
			(at -2.465551 -9.813815 180)
			(unlocked yes)
			(layer "B.SilkS")
			(hide yes)
			(effects
				(font
					(size 0.762 0.762)
					(thickness 0.2032)
				)
				(justify mirror)
			)
		)
		(sheetname "11-M2_RCB_MUX")
		(sheetfile "11-M2_RCB_MUX.kicad_sch")
		(duplicate_pad_numbers_are_jumpers no)
		(fp_line
			(start 0.65607 0.7)
			(end -0.65607 0.7)
			(stroke
				(width 0.2)
				(type solid)
			)
			(layer "B.SilkS")
		)
		(fp_line
			(start 0.65607 -0.7)
			(end -0.65607 -0.7)
			(stroke
				(width 0.2)
				(type solid)
			)
			(layer "B.SilkS")
		)
		(fp_line
			(start -0.75607 0.4)
			(end -0.75607 -0.4)
			(stroke
				(width 0.2)
				(type solid)
			)
			(layer "B.CrtYd")
		)
		(fp_line
			(start 0.75607 0.4)
			(end -0.75607 0.4)
			(stroke
				(width 0.2)
				(type solid)
			)
			(layer "B.CrtYd")
		)
		(fp_line
			(start 0.75607 0.4)
			(end 0.75607 -0.4)
			(stroke
				(width 0.2)
				(type solid)
			)
			(layer "B.CrtYd")
		)
		(fp_line
			(start 0.75607 -0.4)
			(end -0.75607 -0.4)
			(stroke
				(width 0.2)
				(type solid)
			)
			(layer "B.CrtYd")
		)
		(fp_line
			(start 0 0.5)
			(end 0 -0.5)
			(stroke
				(width 0.1)
				(type solid)
			)
			(layer "B.Fab")
		)
		(fp_line
			(start -0.75607 0.4)
			(end -0.75607 -0.4)
			(stroke
				(width 0.2)
				(type solid)
			)
			(layer "B.Fab")
		)
		(fp_line
			(start 0.75607 0.4)
			(end -0.75607 0.4)
			(stroke
				(width 0.2)
				(type solid)
			)
			(layer "B.Fab")
		)
		(fp_line
			(start 0.75607 0.4)
			(end 0.75607 -0.4)
			(stroke
				(width 0.2)
				(type solid)
			)
			(layer "B.Fab")
		)
		(fp_line
			(start 0.5 0)
			(end -0.5 0)
			(stroke
				(width 0.1)
				(type solid)
			)
			(layer "B.Fab")
		)
		(fp_line
			(start 0.75607 -0.4)
			(end -0.75607 -0.4)
			(stroke
				(width 0.2)
				(type solid)
			)
			(layer "B.Fab")
		)
		(fp_text user "${REFERENCE}"
			(at -0.00001 -0.09602 90)
			(unlocked yes)
			(layer "B.Fab")
			(effects
				(font
					(face "Arial")
					(size 0.63 0.63)
					(thickness 0.1)
				)
				(justify left bottom mirror)
			)
		)
		(pad "1" smd rect
			(at -0.36554 0 270)
			(size 0.58106 0.51213)
			(layers "B.Cu" "B.Mask" "B.Paste")
			(net "+3.3V")
			(solder_mask_margin 0)
			(solder_paste_margin 0)
		)
		(pad "2" smd rect
			(at 0.36554 0 270)
			(size 0.58106 0.51213)
			(layers "B.Cu" "B.Mask" "B.Paste")
			(net "GND")
			(solder_mask_margin 0)
			(solder_paste_margin 0)
		)
	)
	(footprint "Vault:RESC1005X40X25NL05T05"
		(layer "B.Cu")
		(at 219.9216 116.5412 -90)
		(property "Reference" "R112"
			(at 0.2782 1.273079 90)
			(unlocked yes)
			(layer "B.SilkS")
			(effects
				(font
					(size 0.762 0.762)
					(thickness 0.2032)
				)
				(justify mirror)
			)
		)
		(property "Value" "200_1%_0402"
			(at -2.732271 -8.112675 180)
			(unlocked yes)
			(layer "B.SilkS")
			(hide yes)
			(effects
				(font
					(size 0.762 0.762)
					(thickness 0.2032)
				)
				(justify mirror)
			)
		)
		(sheetname "08-DIPSwitches_I2C")
		(sheetfile "08-DIPSwitches_I2C.kicad_sch")
		(duplicate_pad_numbers_are_jumpers no)
		(pad "1" smd rect
			(at -0.45 0 180)
			(size 0.55 0.55)
			(layers "B.Cu" "B.Mask" "B.Paste")
			(net "NetD21_1")
		)
		(pad "2" smd rect
			(at 0.45 0 180)
			(size 0.55 0.55)
			(layers "B.Cu" "B.Mask" "B.Paste")
			(net "DIP_SW_UART_SEL")
		)
	)
	(footprint "Vault:RESC1005X40X25LL05T10"
		(layer "B.Cu")
		(at 220.4216 107.6162)
		(property "Reference" "R88"
			(at -2.2286 0.126921 0)
			(unlocked yes)
			(layer "B.SilkS")
			(effects
				(font
					(size 0.762 0.762)
					(thickness 0.2286)
				)
				(justify mirror)
			)
		)
		(property "Value" "10K_1%_0402"
			(at -2.579871 -8.061915 270)
			(unlocked yes)
			(layer "B.SilkS")
			(hide yes)
			(effects
				(font
					(size 0.762 0.762)
					(thickness 0.2286)
				)
				(justify mirror)
			)
		)
		(sheetname "08-DIPSwitches_I2C")
		(sheetfile "08-DIPSwitches_I2C.kicad_sch")
		(duplicate_pad_numbers_are_jumpers no)
		(pad "1" smd rect
			(at -0.375 0 270)
			(size 0.45 0.5)
			(layers "B.Cu" "B.Mask" "B.Paste")
			(net "+3.3V")
		)
		(pad "2" smd rect
			(at 0.375 0 270)
			(size 0.45 0.5)
			(layers "B.Cu" "B.Mask" "B.Paste")
			(net "DIP_SW_PPS_SEL")
		)
	)
	(footprint "Vault:FP-0603-L_1_6_0_2-W_0_8_0-MFG"
		(layer "B.Cu")
		(at 98.0216 66.9162 -90)
		(property "Reference" "C15"
			(at 1.3 -0.493345 90)
			(unlocked yes)
			(layer "B.SilkS")
			(effects
				(font
					(size 0.762 0.762)
					(thickness 0.2286)
				)
				(justify left bottom mirror)
			)
		)
		(property "Value" "10uF_16V_0603"
			(at 0.683315 9.5697 0)
			(unlocked yes)
			(layer "B.SilkS")
			(hide yes)
			(effects
				(font
					(size 0.762 0.762)
					(thickness 0.2286)
				)
				(justify left bottom mirror)
			)
		)
		(sheetname "03-POWER")
		(sheetfile "03-POWER.kicad_sch")
		(duplicate_pad_numbers_are_jumpers no)
		(fp_line
			(start 0.9 0.825)
			(end -0.9 0.825)
			(stroke
				(width 0.2)
				(type solid)
			)
			(layer "B.SilkS")
		)
		(fp_line
			(start 0.9 -0.825)
			(end -0.9 -0.825)
			(stroke
				(width 0.2)
				(type solid)
			)
			(layer "B.SilkS")
		)
		(fp_line
			(start -1.15 0.6)
			(end -1.15 -0.6)
			(stroke
				(width 0.2)
				(type solid)
			)
			(layer "B.CrtYd")
		)
		(fp_line
			(start 1.15 0.6)
			(end -1.15 0.6)
			(stroke
				(width 0.2)
				(type solid)
			)
			(layer "B.CrtYd")
		)
		(fp_line
			(start 1.15 0.6)
			(end 1.15 -0.6)
			(stroke
				(width 0.2)
				(type solid)
			)
			(layer "B.CrtYd")
		)
		(fp_line
			(start 1.15 -0.6)
			(end -1.15 -0.6)
			(stroke
				(width 0.2)
				(type solid)
			)
			(layer "B.CrtYd")
		)
		(fp_line
			(start -1.15 0.6)
			(end -1.15 -0.6)
			(stroke
				(width 0.2)
				(type solid)
			)
			(layer "B.Fab")
		)
		(fp_line
			(start 1.15 0.6)
			(end -1.15 0.6)
			(stroke
				(width 0.2)
				(type solid)
			)
			(layer "B.Fab")
		)
		(fp_line
			(start 1.15 0.6)
			(end 1.15 -0.6)
			(stroke
				(width 0.2)
				(type solid)
			)
			(layer "B.Fab")
		)
		(fp_line
			(start 0 0.5)
			(end 0 -0.5)
			(stroke
				(width 0.1)
				(type solid)
			)
			(layer "B.Fab")
		)
		(fp_line
			(start 0.5 0)
			(end -0.5 0)
			(stroke
				(width 0.1)
				(type solid)
			)
			(layer "B.Fab")
		)
		(fp_line
			(start 1.15 -0.6)
			(end -1.15 -0.6)
			(stroke
				(width 0.2)
				(type solid)
			)
			(layer "B.Fab")
		)
		(fp_text user "${REFERENCE}"
			(at -0.00001 -0.09602 90)
			(unlocked yes)
			(layer "B.Fab")
			(effects
				(font
					(face "Arial")
					(size 0.63 0.63)
					(thickness 0.1)
				)
				(justify left bottom mirror)
			)
		)
		(pad "1" smd rect
			(at -0.7 0 270)
			(size 0.7 0.7)
			(layers "B.Cu" "B.Mask" "B.Paste")
			(net "+5.0V")
			(solder_mask_margin 0)
			(solder_paste_margin 0)
		)
		(pad "2" smd rect
			(at 0.7 0 270)
			(size 0.7 0.7)
			(layers "B.Cu" "B.Mask" "B.Paste")
			(net "GND")
			(solder_mask_margin 0)
			(solder_paste_margin 0)
		)
	)
	(footprint "Vault:RESC1005X40X25LL05T10"
		(layer "B.Cu")
		(at 220.8216 105.1162)
		(property "Reference" "R89"
			(at 1.8714 0.026921 0)
			(unlocked yes)
			(layer "B.SilkS")
			(effects
				(font
					(size 0.762 0.762)
					(thickness 0.2286)
				)
				(justify mirror)
			)
		)
		(property "Value" "10K_1%_0402"
			(at -2.579871 -8.061915 270)
			(unlocked yes)
			(layer "B.SilkS")
			(hide yes)
			(effects
				(font
					(size 0.762 0.762)
					(thickness 0.2286)
				)
				(justify mirror)
			)
		)
		(sheetname "08-DIPSwitches_I2C")
		(sheetfile "08-DIPSwitches_I2C.kicad_sch")
		(duplicate_pad_numbers_are_jumpers no)
		(pad "1" smd rect
			(at -0.375 0 270)
			(size 0.45 0.5)
			(layers "B.Cu" "B.Mask" "B.Paste")
			(net "+3.3V")
		)
		(pad "2" smd rect
			(at 0.375 0 270)
			(size 0.45 0.5)
			(layers "B.Cu" "B.Mask" "B.Paste")
			(net "DIP_SW_MACSER_SEL")
		)
	)
	(footprint "Vault:RESC1005X40X25LL05T05"
		(layer "B.Cu")
		(at 168.15457 94.6162 90)
		(property "Reference" "R79"
			(at 0.2286 0.940099 270)
			(unlocked yes)
			(layer "B.SilkS")
			(effects
				(font
					(size 0.762 0.762)
					(thickness 0.2286)
				)
				(justify mirror)
			)
		)
		(property "Value" "0_1%_0402"
			(at -2.579871 -6.66536 0)
			(unlocked yes)
			(layer "B.SilkS")
			(hide yes)
			(effects
				(font
					(size 0.762 0.762)
					(thickness 0.2286)
				)
				(justify mirror)
			)
		)
		(sheetname "03-POWER")
		(sheetfile "03-POWER.kicad_sch")
		(duplicate_pad_numbers_are_jumpers no)
		(pad "1" smd rect
			(at -0.4 0)
			(size 0.45 0.45)
			(layers "B.Cu" "B.Mask" "B.Paste")
			(net "NetR79_1")
		)
		(pad "2" smd rect
			(at 0.4 0)
			(size 0.45 0.45)
			(layers "B.Cu" "B.Mask" "B.Paste")
			(net "GND")
		)
	)
)
